(kicad_pcb
	(version 20260206)
	(generator "pcbnew")
	(generator_version "10.0")
	(general
		(thickness 1.6)
		(legacy_teardrops no)
	)
	(paper "A4")
	(title_block
		(title "04192023_DAF0TMB3IC0_F0TG_MB_C_brd_V02_OCP.brd")
		(comment 1 "Grand Teton / footprints 2904-2908 of 8354")
	)
	(layers
		(0 "F.Cu" signal "TOP")
		(4 "In1.Cu" signal "GND")
		(6 "In2.Cu" signal "IN1")
		(8 "In3.Cu" signal "GND1")
		(10 "In4.Cu" signal "IN2")
		(12 "In5.Cu" signal "GND2")
		(14 "In6.Cu" signal "IN3")
		(16 "In7.Cu" signal "GND3")
		(18 "In8.Cu" signal "VCC")
		(20 "In9.Cu" signal "VCC1")
		(22 "In10.Cu" signal "GND4")
		(24 "In11.Cu" signal "IN4")
		(26 "In12.Cu" signal "GND5")
		(28 "In13.Cu" signal "IN5")
		(30 "In14.Cu" signal "GND6")
		(32 "In15.Cu" signal "IN6")
		(34 "In16.Cu" signal "GND7")
		(2 "B.Cu" signal "BOTTOM")
		(9 "F.Adhes" user "F.Adhesive")
		(11 "B.Adhes" user "B.Adhesive")
		(13 "F.Paste" user "Package Geometry/Pastemask Top")
		(15 "B.Paste" user "Package Geometry/Pastemask Bottom")
		(5 "F.SilkS" user "Ref Des/Silkscreen Top")
		(7 "B.SilkS" user "Ref Des/Silkscreen Bottom")
		(1 "F.Mask" user "Board Geometry/Soldermask Top")
		(3 "B.Mask" user "Board Geometry/Soldermask Bottom")
		(17 "Dwgs.User" user "User.Drawings")
		(19 "Cmts.User" user "User.Comments")
		(21 "Eco1.User" user "User.Eco1")
		(23 "Eco2.User" user "User.Eco2")
		(25 "Edge.Cuts" user "Board Geometry/Outline")
		(27 "Margin" user)
		(31 "F.CrtYd" user "Package Geometry/Place Bound Top")
		(29 "B.CrtYd" user "Package Geometry/Place Bound Bottom")
		(35 "F.Fab" user "Ref Des/Assembly Top")
		(33 "B.Fab" user "Ref Des/Assembly Bottom")
	)
	(footprint ""
		(layer "F.Cu")
		(at 197.979538 -339.282024 90)
		(property "Reference" "PC118"
			(at 0 0 90)
			(layer "F.SilkS")
			(hide yes)
			(effects
				(font
					(size 1.27 1.27)
				)
			)
		)
		(property "Value" ""
			(at 0 0 90)
			(layer "F.Fab")
			(effects
				(font
					(size 1.27 1.27)
				)
			)
		)
		(duplicate_pad_numbers_are_jumpers no)
		(fp_line
			(start 0.7874 -0.4064)
			(end 0.7874 0.4064)
			(stroke
				(width 0.1524)
				(type default)
			)
			(layer "F.SilkS")
		)
		(fp_line
			(start -0.7874 -0.4064)
			(end 0.7874 -0.4064)
			(stroke
				(width 0.1524)
				(type default)
			)
			(layer "F.SilkS")
		)
		(fp_line
			(start 0.7874 0.4064)
			(end -0.7874 0.4064)
			(stroke
				(width 0.1524)
				(type default)
			)
			(layer "F.SilkS")
		)
		(fp_line
			(start -0.7874 0.4064)
			(end -0.7874 -0.4064)
			(stroke
				(width 0.1524)
				(type default)
			)
			(layer "F.SilkS")
		)
		(fp_line
			(start -0.12065 -0.305054)
			(end -0.12065 -0.2794)
			(stroke
				(width 0.1)
				(type default)
			)
			(layer "F.Fab")
		)
		(fp_line
			(start -0.67945 -0.305054)
			(end -0.12065 -0.305054)
			(stroke
				(width 0.1)
				(type default)
			)
			(layer "F.Fab")
		)
		(fp_line
			(start 0.67945 -0.3048)
			(end 0.67945 0.3048)
			(stroke
				(width 0.1)
				(type default)
			)
			(layer "F.Fab")
		)
		(fp_line
			(start 0.12065 -0.3048)
			(end 0.67945 -0.3048)
			(stroke
				(width 0.1)
				(type default)
			)
			(layer "F.Fab")
		)
		(fp_line
			(start 0.12065 -0.2794)
			(end 0.12065 -0.3048)
			(stroke
				(width 0.1)
				(type default)
			)
			(layer "F.Fab")
		)
		(fp_line
			(start -0.12065 -0.2794)
			(end 0.12065 -0.2794)
			(stroke
				(width 0.1)
				(type default)
			)
			(layer "F.Fab")
		)
		(fp_line
			(start 0.120396 0.2794)
			(end -0.12065 0.2794)
			(stroke
				(width 0.1)
				(type default)
			)
			(layer "F.Fab")
		)
		(fp_line
			(start -0.12065 0.2794)
			(end -0.12065 0.3048)
			(stroke
				(width 0.1)
				(type default)
			)
			(layer "F.Fab")
		)
		(fp_line
			(start 0.67945 0.3048)
			(end 0.120396 0.3048)
			(stroke
				(width 0.1)
				(type default)
			)
			(layer "F.Fab")
		)
		(fp_line
			(start 0.120396 0.3048)
			(end 0.120396 0.2794)
			(stroke
				(width 0.1)
				(type default)
			)
			(layer "F.Fab")
		)
		(fp_line
			(start -0.12065 0.3048)
			(end -0.67945 0.3048)
			(stroke
				(width 0.1)
				(type default)
			)
			(layer "F.Fab")
		)
		(fp_line
			(start -0.67945 0.3048)
			(end -0.67945 -0.305054)
			(stroke
				(width 0.1)
				(type default)
			)
			(layer "F.Fab")
		)
		(pad "1" smd circle
			(at -0.40005 0 90)
			(size 0 0)
			(layers "F.Cu" "F.Mask" "F.Paste")
			(net "PVDD_33_S5_VCC")
		)
		(pad "2" smd circle
			(at 0.40005 0 90)
			(size 0 0)
			(layers "F.Cu" "F.Mask" "F.Paste")
			(net "GND")
		)
	)
	(footprint ""
		(layer "F.Cu")
		(at 104.488488 -344.591132 90)
		(property "Reference" "PR428"
			(at 0 0 90)
			(layer "F.SilkS")
			(hide yes)
			(effects
				(font
					(size 1.27 1.27)
				)
			)
		)
		(property "Value" ""
			(at 0 0 90)
			(layer "F.Fab")
			(effects
				(font
					(size 1.27 1.27)
				)
			)
		)
		(duplicate_pad_numbers_are_jumpers no)
		(fp_line
			(start 0.7874 -0.4064)
			(end 0.7874 0.4064)
			(stroke
				(width 0.1524)
				(type default)
			)
			(layer "F.SilkS")
		)
		(fp_line
			(start -0.7874 -0.4064)
			(end 0.7874 -0.4064)
			(stroke
				(width 0.1524)
				(type default)
			)
			(layer "F.SilkS")
		)
		(fp_line
			(start 0.7874 0.4064)
			(end -0.7874 0.4064)
			(stroke
				(width 0.1524)
				(type default)
			)
			(layer "F.SilkS")
		)
		(fp_line
			(start -0.7874 0.4064)
			(end -0.7874 -0.4064)
			(stroke
				(width 0.1524)
				(type default)
			)
			(layer "F.SilkS")
		)
		(fp_line
			(start -0.12065 -0.305054)
			(end -0.12065 -0.2794)
			(stroke
				(width 0.1)
				(type default)
			)
			(layer "F.Fab")
		)
		(fp_line
			(start -0.67945 -0.305054)
			(end -0.12065 -0.305054)
			(stroke
				(width 0.1)
				(type default)
			)
			(layer "F.Fab")
		)
		(fp_line
			(start 0.67945 -0.3048)
			(end 0.67945 0.3048)
			(stroke
				(width 0.1)
				(type default)
			)
			(layer "F.Fab")
		)
		(fp_line
			(start 0.12065 -0.3048)
			(end 0.67945 -0.3048)
			(stroke
				(width 0.1)
				(type default)
			)
			(layer "F.Fab")
		)
		(fp_line
			(start 0.12065 -0.2794)
			(end 0.12065 -0.3048)
			(stroke
				(width 0.1)
				(type default)
			)
			(layer "F.Fab")
		)
		(fp_line
			(start -0.12065 -0.2794)
			(end 0.12065 -0.2794)
			(stroke
				(width 0.1)
				(type default)
			)
			(layer "F.Fab")
		)
		(fp_line
			(start 0.120396 0.2794)
			(end -0.12065 0.2794)
			(stroke
				(width 0.1)
				(type default)
			)
			(layer "F.Fab")
		)
		(fp_line
			(start -0.12065 0.2794)
			(end -0.12065 0.3048)
			(stroke
				(width 0.1)
				(type default)
			)
			(layer "F.Fab")
		)
		(fp_line
			(start 0.67945 0.3048)
			(end 0.120396 0.3048)
			(stroke
				(width 0.1)
				(type default)
			)
			(layer "F.Fab")
		)
		(fp_line
			(start 0.120396 0.3048)
			(end 0.120396 0.2794)
			(stroke
				(width 0.1)
				(type default)
			)
			(layer "F.Fab")
		)
		(fp_line
			(start -0.12065 0.3048)
			(end -0.67945 0.3048)
			(stroke
				(width 0.1)
				(type default)
			)
			(layer "F.Fab")
		)
		(fp_line
			(start -0.67945 0.3048)
			(end -0.67945 -0.305054)
			(stroke
				(width 0.1)
				(type default)
			)
			(layer "F.Fab")
		)
		(pad "1" smd circle
			(at -0.40005 0 90)
			(size 0 0)
			(layers "F.Cu" "F.Mask" "F.Paste")
			(net "SW_PVDDCR_CPU1_P1_BOOT6")
		)
		(pad "2" smd circle
			(at 0.40005 0 90)
			(size 0 0)
			(layers "F.Cu" "F.Mask" "F.Paste")
			(net "SW_PVDDCR_CPU1_P1_BOOT6_R")
		)
	)
	(footprint ""
		(layer "F.Cu")
		(at 279.513792 -123.035314 180)
		(property "Reference" "R319"
			(at 0 0 180)
			(layer "F.SilkS")
			(hide yes)
			(effects
				(font
					(size 1.27 1.27)
				)
			)
		)
		(property "Value" ""
			(at 0 0 180)
			(layer "F.Fab")
			(effects
				(font
					(size 1.27 1.27)
				)
			)
		)
		(duplicate_pad_numbers_are_jumpers no)
		(fp_line
			(start 0.7874 0.4064)
			(end -0.7874 0.4064)
			(stroke
				(width 0.1524)
				(type default)
			)
			(layer "F.SilkS")
		)
		(fp_line
			(start 0.7874 -0.4064)
			(end 0.7874 0.4064)
			(stroke
				(width 0.1524)
				(type default)
			)
			(layer "F.SilkS")
		)
		(fp_line
			(start -0.7874 0.4064)
			(end -0.7874 -0.4064)
			(stroke
				(width 0.1524)
				(type default)
			)
			(layer "F.SilkS")
		)
		(fp_line
			(start -0.7874 -0.4064)
			(end 0.7874 -0.4064)
			(stroke
				(width 0.1524)
				(type default)
			)
			(layer "F.SilkS")
		)
		(fp_line
			(start 0.67945 0.3048)
			(end 0.120396 0.3048)
			(stroke
				(width 0.1)
				(type default)
			)
			(layer "F.Fab")
		)
		(fp_line
			(start 0.67945 -0.3048)
			(end 0.67945 0.3048)
			(stroke
				(width 0.1)
				(type default)
			)
			(layer "F.Fab")
		)
		(fp_line
			(start 0.12065 -0.2794)
			(end 0.12065 -0.3048)
			(stroke
				(width 0.1)
				(type default)
			)
			(layer "F.Fab")
		)
		(fp_line
			(start 0.12065 -0.3048)
			(end 0.67945 -0.3048)
			(stroke
				(width 0.1)
				(type default)
			)
			(layer "F.Fab")
		)
		(fp_line
			(start 0.120396 0.3048)
			(end 0.120396 0.2794)
			(stroke
				(width 0.1)
				(type default)
			)
			(layer "F.Fab")
		)
		(fp_line
			(start 0.120396 0.2794)
			(end -0.12065 0.2794)
			(stroke
				(width 0.1)
				(type default)
			)
			(layer "F.Fab")
		)
		(fp_line
			(start -0.12065 0.3048)
			(end -0.67945 0.3048)
			(stroke
				(width 0.1)
				(type default)
			)
			(layer "F.Fab")
		)
		(fp_line
			(start -0.12065 0.2794)
			(end -0.12065 0.3048)
			(stroke
				(width 0.1)
				(type default)
			)
			(layer "F.Fab")
		)
		(fp_line
			(start -0.12065 -0.2794)
			(end 0.12065 -0.2794)
			(stroke
				(width 0.1)
				(type default)
			)
			(layer "F.Fab")
		)
		(fp_line
			(start -0.12065 -0.305054)
			(end -0.12065 -0.2794)
			(stroke
				(width 0.1)
				(type default)
			)
			(layer "F.Fab")
		)
		(fp_line
			(start -0.67945 0.3048)
			(end -0.67945 -0.305054)
			(stroke
				(width 0.1)
				(type default)
			)
			(layer "F.Fab")
		)
		(fp_line
			(start -0.67945 -0.305054)
			(end -0.12065 -0.305054)
			(stroke
				(width 0.1)
				(type default)
			)
			(layer "F.Fab")
		)
		(pad "1" smd circle
			(at -0.40005 0 180)
			(size 0 0)
			(layers "F.Cu" "F.Mask" "F.Paste")
			(net "PCA9548_PCIE3_ADDR1")
		)
		(pad "2" smd circle
			(at 0.40005 0 180)
			(size 0 0)
			(layers "F.Cu" "F.Mask" "F.Paste")
			(net "GND")
		)
	)
	(footprint ""
		(layer "F.Cu")
		(at 30.569662 -419.249098 -90)
		(property "Reference" "R3272"
			(at 0 0 270)
			(layer "F.SilkS")
			(hide yes)
			(effects
				(font
					(size 1.27 1.27)
				)
			)
		)
		(property "Value" ""
			(at 0 0 270)
			(layer "F.Fab")
			(effects
				(font
					(size 1.27 1.27)
				)
			)
		)
		(duplicate_pad_numbers_are_jumpers no)
		(fp_line
			(start -0.7874 0.4064)
			(end -0.7874 -0.4064)
			(stroke
				(width 0.1524)
				(type default)
			)
			(layer "F.SilkS")
		)
		(fp_line
			(start 0.7874 0.4064)
			(end -0.7874 0.4064)
			(stroke
				(width 0.1524)
				(type default)
			)
			(layer "F.SilkS")
		)
		(fp_line
			(start -0.7874 -0.4064)
			(end 0.7874 -0.4064)
			(stroke
				(width 0.1524)
				(type default)
			)
			(layer "F.SilkS")
		)
		(fp_line
			(start 0.7874 -0.4064)
			(end 0.7874 0.4064)
			(stroke
				(width 0.1524)
				(type default)
			)
			(layer "F.SilkS")
		)
		(fp_line
			(start -0.67945 0.3048)
			(end -0.67945 -0.305054)
			(stroke
				(width 0.1)
				(type default)
			)
			(layer "F.Fab")
		)
		(fp_line
			(start -0.12065 0.3048)
			(end -0.67945 0.3048)
			(stroke
				(width 0.1)
				(type default)
			)
			(layer "F.Fab")
		)
		(fp_line
			(start 0.120396 0.3048)
			(end 0.120396 0.2794)
			(stroke
				(width 0.1)
				(type default)
			)
			(layer "F.Fab")
		)
		(fp_line
			(start 0.67945 0.3048)
			(end 0.120396 0.3048)
			(stroke
				(width 0.1)
				(type default)
			)
			(layer "F.Fab")
		)
		(fp_line
			(start -0.12065 0.2794)
			(end -0.12065 0.3048)
			(stroke
				(width 0.1)
				(type default)
			)
			(layer "F.Fab")
		)
		(fp_line
			(start 0.120396 0.2794)
			(end -0.12065 0.2794)
			(stroke
				(width 0.1)
				(type default)
			)
			(layer "F.Fab")
		)
		(fp_line
			(start -0.12065 -0.2794)
			(end 0.12065 -0.2794)
			(stroke
				(width 0.1)
				(type default)
			)
			(layer "F.Fab")
		)
		(fp_line
			(start 0.12065 -0.2794)
			(end 0.12065 -0.3048)
			(stroke
				(width 0.1)
				(type default)
			)
			(layer "F.Fab")
		)
		(fp_line
			(start 0.12065 -0.3048)
			(end 0.67945 -0.3048)
			(stroke
				(width 0.1)
				(type default)
			)
			(layer "F.Fab")
		)
		(fp_line
			(start 0.67945 -0.3048)
			(end 0.67945 0.3048)
			(stroke
				(width 0.1)
				(type default)
			)
			(layer "F.Fab")
		)
		(fp_line
			(start -0.67945 -0.305054)
			(end -0.12065 -0.305054)
			(stroke
				(width 0.1)
				(type default)
			)
			(layer "F.Fab")
		)
		(fp_line
			(start -0.12065 -0.305054)
			(end -0.12065 -0.2794)
			(stroke
				(width 0.1)
				(type default)
			)
			(layer "F.Fab")
		)
		(pad "1" smd circle
			(at -0.40005 0 270)
			(size 0 0)
			(layers "F.Cu" "F.Mask" "F.Paste")
			(net "FM_P2E_EQA1")
		)
		(pad "2" smd circle
			(at 0.40005 0 270)
			(size 0 0)
			(layers "F.Cu" "F.Mask" "F.Paste")
			(net "GND")
		)
	)
	(footprint ""
		(layer "F.Cu")
		(at 306.420266 -430.240186 180)
		(property "Reference" "C19"
			(at 0 0 180)
			(layer "F.SilkS")
			(hide yes)
			(effects
				(font
					(size 1.27 1.27)
				)
			)
		)
		(property "Value" ""
			(at 0 0 180)
			(layer "F.Fab")
			(effects
				(font
					(size 1.27 1.27)
				)
			)
		)
		(duplicate_pad_numbers_are_jumpers no)
		(fp_line
			(start 0.7874 0.4064)
			(end -0.7874 0.4064)
			(stroke
				(width 0.1524)
				(type default)
			)
			(layer "F.SilkS")
		)
		(fp_line
			(start 0.7874 -0.4064)
			(end 0.7874 0.4064)
			(stroke
				(width 0.1524)
				(type default)
			)
			(layer "F.SilkS")
		)
		(fp_line
			(start -0.7874 0.4064)
			(end -0.7874 -0.4064)
			(stroke
				(width 0.1524)
				(type default)
			)
			(layer "F.SilkS")
		)
		(fp_line
			(start -0.7874 -0.4064)
			(end 0.7874 -0.4064)
			(stroke
				(width 0.1524)
				(type default)
			)
			(layer "F.SilkS")
		)
		(fp_line
			(start 0.67945 0.3048)
			(end 0.120396 0.3048)
			(stroke
				(width 0.1)
				(type default)
			)
			(layer "F.Fab")
		)
		(fp_line
			(start 0.67945 -0.3048)
			(end 0.67945 0.3048)
			(stroke
				(width 0.1)
				(type default)
			)
			(layer "F.Fab")
		)
		(fp_line
			(start 0.12065 -0.2794)
			(end 0.12065 -0.3048)
			(stroke
				(width 0.1)
				(type default)
			)
			(layer "F.Fab")
		)
		(fp_line
			(start 0.12065 -0.3048)
			(end 0.67945 -0.3048)
			(stroke
				(width 0.1)
				(type default)
			)
			(layer "F.Fab")
		)
		(fp_line
			(start 0.120396 0.3048)
			(end 0.120396 0.2794)
			(stroke
				(width 0.1)
				(type default)
			)
			(layer "F.Fab")
		)
		(fp_line
			(start 0.120396 0.2794)
			(end -0.12065 0.2794)
			(stroke
				(width 0.1)
				(type default)
			)
			(layer "F.Fab")
		)
		(fp_line
			(start -0.12065 0.3048)
			(end -0.67945 0.3048)
			(stroke
				(width 0.1)
				(type default)
			)
			(layer "F.Fab")
		)
		(fp_line
			(start -0.12065 0.2794)
			(end -0.12065 0.3048)
			(stroke
				(width 0.1)
				(type default)
			)
			(layer "F.Fab")
		)
		(fp_line
			(start -0.12065 -0.2794)
			(end 0.12065 -0.2794)
			(stroke
				(width 0.1)
				(type default)
			)
			(layer "F.Fab")
		)
		(fp_line
			(start -0.12065 -0.305054)
			(end -0.12065 -0.2794)
			(stroke
				(width 0.1)
				(type default)
			)
			(layer "F.Fab")
		)
		(fp_line
			(start -0.67945 0.3048)
			(end -0.67945 -0.305054)
			(stroke
				(width 0.1)
				(type default)
			)
			(layer "F.Fab")
		)
		(fp_line
			(start -0.67945 -0.305054)
			(end -0.12065 -0.305054)
			(stroke
				(width 0.1)
				(type default)
			)
			(layer "F.Fab")
		)
		(pad "1" smd circle
			(at -0.40005 0 180)
			(size 0 0)
			(layers "F.Cu" "F.Mask" "F.Paste")
			(net "PRSNT_CABLE_GPU_A2_ISO_N")
		)
		(pad "2" smd circle
			(at 0.40005 0 180)
			(size 0 0)
			(layers "F.Cu" "F.Mask" "F.Paste")
			(net "GND")
		)
	)
)
